(kicad_pcb
	(version 20260206)
	(generator "pcbnew")
	(generator_version "10.0")
	(general
		(thickness 1.6)
		(legacy_teardrops no)
	)
	(paper "A4")
	(title_block
		(title "Bryce Canyon_IOM_M2_16342-2_OCP.brd")
		(comment 1 "Bryce Canyon / footprints 463-469 of 1146")
	)
	(layers
		(0 "F.Cu" signal "TOP")
		(4 "In1.Cu" signal "L2GND")
		(6 "In2.Cu" signal "L3")
		(8 "In3.Cu" signal "L4VCC")
		(10 "In4.Cu" signal "L5VCC")
		(12 "In5.Cu" signal "L6")
		(14 "In6.Cu" signal "L7GND")
		(2 "B.Cu" signal "BOTTOM")
		(9 "F.Adhes" user "F.Adhesive")
		(11 "B.Adhes" user "B.Adhesive")
		(13 "F.Paste" user "Package Geometry/Pastemask Top")
		(15 "B.Paste" user "Package Geometry/Pastemask Bottom")
		(5 "F.SilkS" user "Ref Des/Silkscreen Top")
		(7 "B.SilkS" user "Ref Des/Silkscreen Bottom")
		(1 "F.Mask" user "Board Geometry/Soldermask Top")
		(3 "B.Mask" user "Board Geometry/Soldermask Bottom")
		(17 "Dwgs.User" user "User.Drawings")
		(19 "Cmts.User" user "User.Comments")
		(21 "Eco1.User" user "User.Eco1")
		(23 "Eco2.User" user "User.Eco2")
		(25 "Edge.Cuts" user "Board Geometry/Outline")
		(27 "Margin" user)
		(31 "F.CrtYd" user "Package Geometry/Place Bound Top")
		(29 "B.CrtYd" user "Package Geometry/Place Bound Bottom")
		(35 "F.Fab" user "Ref Des/Assembly Top")
		(33 "B.Fab" user "Ref Des/Assembly Bottom")
	)
	(footprint ""
		(layer "F.Cu")
		(at 93.875606 -129.811526 -90)
		(property "Reference" "U33"
			(at 0 0 270)
			(layer "F.SilkS")
			(hide yes)
			(effects
				(font
					(size 1.27 1.27)
				)
			)
		)
		(property "Value" "TS5A23157DGSR-GP"
			(at 0 -11.1252 270)
			(unlocked yes)
			(layer "F.Fab")
			(hide yes)
			(effects
				(font
					(size 1.016 1.016)
					(thickness 0.1524)
				)
			)
		)
		(property "Device Type" "MSOP10H44"
			(at 0 -12.6492 270)
			(unlocked yes)
			(layer "F.Fab")
			(hide yes)
			(effects
				(font
					(size 1.016 1.016)
					(thickness 0.1524)
				)
			)
		)
		(duplicate_pad_numbers_are_jumpers no)
		(fp_line
			(start -2.0066 1.016)
			(end -2.0066 -1.016)
			(stroke
				(width 0.1524)
				(type default)
			)
			(layer "F.SilkS")
		)
		(fp_line
			(start -1.8288 1.016)
			(end -1.8288 3.048)
			(stroke
				(width 0.508)
				(type default)
			)
			(layer "F.SilkS")
		)
		(fp_line
			(start 1.143 1.016)
			(end -2.0066 1.016)
			(stroke
				(width 0.1524)
				(type default)
			)
			(layer "F.SilkS")
		)
		(fp_line
			(start -1.5748 0)
			(end -1.9558 0.381)
			(stroke
				(width 0.1524)
				(type default)
			)
			(layer "F.SilkS")
		)
		(fp_line
			(start -1.5748 0)
			(end -1.9558 -0.381)
			(stroke
				(width 0.1524)
				(type default)
			)
			(layer "F.SilkS")
		)
		(fp_line
			(start -2.0066 -1.016)
			(end 1.143 -1.016)
			(stroke
				(width 0.1524)
				(type default)
			)
			(layer "F.SilkS")
		)
		(fp_line
			(start 1.143 -1.016)
			(end 1.143 1.016)
			(stroke
				(width 0.1524)
				(type default)
			)
			(layer "F.SilkS")
		)
		(fp_poly
			(pts
				(xy -2.0828 3.3401) (xy 2.0828 3.3401) (xy 2.0828 -3.3401) (xy -2.0828 -3.3401)
			)
			(stroke
				(width 0)
				(type default)
			)
			(fill no)
			(layer "F.CrtYd")
		)
		(fp_poly
			(pts
				(xy -2.0828 3.3401) (xy 2.0828 3.3401) (xy 2.0828 -3.3401) (xy -2.0828 -3.3401)
			)
			(stroke
				(width 0)
				(type default)
			)
			(fill no)
			(layer "F.Fab")
		)
		(pad "1" smd rect
			(at -0.99949 2.0701 270)
			(size 0.3048 1.524)
			(layers "F.Cu" "F.Mask" "F.Paste")
			(net "UART_SEL_MUX")
		)
		(pad "2" smd rect
			(at -0.50038 2.0701 270)
			(size 0.3048 1.524)
			(layers "F.Cu" "F.Mask" "F.Paste")
			(net "UART_BMC_TX")
		)
		(pad "3" smd rect
			(at 0 2.0701 270)
			(size 0.3048 1.524)
			(layers "F.Cu" "F.Mask" "F.Paste")
			(net "GND")
		)
		(pad "4" smd rect
			(at 0.50038 2.0701 270)
			(size 0.3048 1.524)
			(layers "F.Cu" "F.Mask" "F.Paste")
			(net "UART_BMC_RX")
		)
		(pad "5" smd rect
			(at 0.99949 2.0701 270)
			(size 0.3048 1.524)
			(layers "F.Cu" "F.Mask" "F.Paste")
			(net "UART_SEL_MUX")
		)
		(pad "6" smd rect
			(at 0.99949 -2.0701 270)
			(size 0.3048 1.524)
			(layers "F.Cu" "F.Mask" "F.Paste")
			(net "DEBUG_UART_IOM_RX")
		)
		(pad "7" smd rect
			(at 0.50038 -2.0701 270)
			(size 0.3048 1.524)
			(layers "F.Cu" "F.Mask" "F.Paste")
			(net "UART_COMP_IN_RX")
		)
		(pad "8" smd rect
			(at 0 -2.0701 270)
			(size 0.3048 1.524)
			(layers "F.Cu" "F.Mask" "F.Paste")
			(net "P3V3_STBY")
		)
		(pad "9" smd rect
			(at -0.50038 -2.0701 270)
			(size 0.3048 1.524)
			(layers "F.Cu" "F.Mask" "F.Paste")
			(net "UART_COMP_OUT_TX")
		)
		(pad "10" smd rect
			(at -0.99949 -2.0701 270)
			(size 0.3048 1.524)
			(layers "F.Cu" "F.Mask" "F.Paste")
			(net "DEBUG_UART_IOM_TX")
		)
	)
	(footprint ""
		(layer "F.Cu")
		(at 118.9736 -16.002)
		(property "Reference" "R440"
			(at 0 0 0)
			(layer "F.SilkS")
			(hide yes)
			(effects
				(font
					(size 1.27 1.27)
				)
			)
		)
		(property "Value" "10R2F-L-GP"
			(at 0.064008 -3.993896 0)
			(unlocked yes)
			(layer "F.Fab")
			(hide yes)
			(effects
				(font
					(size 1.016 1.016)
					(thickness 0.1524)
				)
			)
		)
		(property "Device Type" "R402H14"
			(at 0.064008 -5.517896 0)
			(unlocked yes)
			(layer "F.Fab")
			(hide yes)
			(effects
				(font
					(size 1.016 1.016)
					(thickness 0.1524)
				)
			)
		)
		(duplicate_pad_numbers_are_jumpers no)
		(fp_line
			(start -0.508 -0.9398)
			(end -0.508 0.9398)
			(stroke
				(width 0.1524)
				(type default)
			)
			(layer "F.SilkS")
		)
		(fp_line
			(start 0.508 -0.9398)
			(end -0.508 -0.9398)
			(stroke
				(width 0.1524)
				(type default)
			)
			(layer "F.SilkS")
		)
		(fp_rect
			(start -0.508 0.9398)
			(end 0.508 -0.9398)
			(stroke
				(width 0)
				(type default)
			)
			(fill no)
			(layer "F.CrtYd")
		)
		(fp_rect
			(start -0.508 0.9398)
			(end 0.508 -0.9398)
			(stroke
				(width 0)
				(type default)
			)
			(fill no)
			(layer "F.Fab")
		)
		(pad "1" smd custom
			(at 0 -0.4445)
			(size 0.1397 0.1397)
			(layers "F.Cu" "F.Mask" "F.Paste")
			(net "MB0_CM_SENSE_R1_P")
			(options
				(clearance outline)
				(anchor circle)
			)
			(primitives
				(gr_poly
					(pts
						(arc
							(start -0.1778 -0.2794)
							(mid -0.249642 -0.249642)
							(end -0.2794 -0.1778)
						)
						(arc
							(start -0.2794 0.1778)
							(mid -0.249642 0.249642)
							(end -0.1778 0.2794)
						)
						(arc
							(start 0.1778 0.2794)
							(mid 0.249642 0.249642)
							(end 0.2794 0.1778)
						)
						(arc
							(start 0.2794 -0.1778)
							(mid 0.249642 -0.249642)
							(end 0.1778 -0.2794)
						)
					)
					(width 0)
					(fill yes)
				)
			)
		)
		(pad "2" smd custom
			(at 0 0.4445)
			(size 0.1397 0.1397)
			(layers "F.Cu" "F.Mask" "F.Paste")
			(net "MB0_CM_SENSE_P")
			(options
				(clearance outline)
				(anchor circle)
			)
			(primitives
				(gr_poly
					(pts
						(arc
							(start -0.1778 -0.2794)
							(mid -0.249642 -0.249642)
							(end -0.2794 -0.1778)
						)
						(arc
							(start -0.2794 0.1778)
							(mid -0.249642 0.249642)
							(end -0.1778 0.2794)
						)
						(arc
							(start 0.1778 0.2794)
							(mid 0.249642 0.249642)
							(end 0.2794 0.1778)
						)
						(arc
							(start 0.2794 -0.1778)
							(mid 0.249642 -0.249642)
							(end 0.1778 -0.2794)
						)
					)
					(width 0)
					(fill yes)
				)
			)
		)
	)
	(footprint ""
		(layer "F.Cu")
		(at 60.452 -158.369)
		(property "Reference" "R397"
			(at 0 0 0)
			(layer "F.SilkS")
			(hide yes)
			(effects
				(font
					(size 1.27 1.27)
				)
			)
		)
		(property "Value" "4K7R2F-GP"
			(at 0.064008 -3.993896 0)
			(unlocked yes)
			(layer "F.Fab")
			(hide yes)
			(effects
				(font
					(size 1.016 1.016)
					(thickness 0.1524)
				)
			)
		)
		(property "Device Type" "R402H16"
			(at 0.064008 -5.517896 0)
			(unlocked yes)
			(layer "F.Fab")
			(hide yes)
			(effects
				(font
					(size 1.016 1.016)
					(thickness 0.1524)
				)
			)
		)
		(duplicate_pad_numbers_are_jumpers no)
		(fp_line
			(start -0.508 -0.9398)
			(end -0.508 0.9398)
			(stroke
				(width 0.1524)
				(type default)
			)
			(layer "F.SilkS")
		)
		(fp_line
			(start 0.508 -0.9398)
			(end -0.508 -0.9398)
			(stroke
				(width 0.1524)
				(type default)
			)
			(layer "F.SilkS")
		)
		(fp_rect
			(start -0.508 0.9398)
			(end 0.508 -0.9398)
			(stroke
				(width 0)
				(type default)
			)
			(fill no)
			(layer "F.CrtYd")
		)
		(fp_rect
			(start -0.508 0.9398)
			(end 0.508 -0.9398)
			(stroke
				(width 0)
				(type default)
			)
			(fill no)
			(layer "F.Fab")
		)
		(pad "1" smd custom
			(at 0 -0.4445)
			(size 0.1397 0.1397)
			(layers "F.Cu" "F.Mask" "F.Paste")
			(net "GND")
			(options
				(clearance outline)
				(anchor circle)
			)
			(primitives
				(gr_poly
					(pts
						(arc
							(start -0.1778 -0.2794)
							(mid -0.249642 -0.249642)
							(end -0.2794 -0.1778)
						)
						(arc
							(start -0.2794 0.1778)
							(mid -0.249642 0.249642)
							(end -0.1778 0.2794)
						)
						(arc
							(start 0.1778 0.2794)
							(mid 0.249642 0.249642)
							(end 0.2794 0.1778)
						)
						(arc
							(start 0.2794 -0.1778)
							(mid 0.249642 -0.249642)
							(end 0.1778 -0.2794)
						)
					)
					(width 0)
					(fill yes)
				)
			)
		)
		(pad "2" smd custom
			(at 0 0.4445)
			(size 0.1397 0.1397)
			(layers "F.Cu" "F.Mask" "F.Paste")
			(net "MAC2_TXD1")
			(options
				(clearance outline)
				(anchor circle)
			)
			(primitives
				(gr_poly
					(pts
						(arc
							(start -0.1778 -0.2794)
							(mid -0.249642 -0.249642)
							(end -0.2794 -0.1778)
						)
						(arc
							(start -0.2794 0.1778)
							(mid -0.249642 0.249642)
							(end -0.1778 0.2794)
						)
						(arc
							(start 0.1778 0.2794)
							(mid 0.249642 0.249642)
							(end 0.2794 0.1778)
						)
						(arc
							(start 0.2794 -0.1778)
							(mid 0.249642 -0.249642)
							(end 0.1778 -0.2794)
						)
					)
					(width 0)
					(fill yes)
				)
			)
		)
	)
	(footprint ""
		(layer "F.Cu")
		(at 168.617138 -9.171178)
		(property "Reference" "C216"
			(at 0 0 0)
			(layer "F.SilkS")
			(hide yes)
			(effects
				(font
					(size 1.27 1.27)
				)
			)
		)
		(property "Value" "SC10U6D3V5KX-4GP"
			(at -0.0762 -6.1214 0)
			(unlocked yes)
			(layer "F.Fab")
			(hide yes)
			(effects
				(font
					(size 1.016 1.016)
					(thickness 0.1524)
				)
			)
		)
		(property "Device Type" "C805H58"
			(at -0.0762 -8.1534 0)
			(unlocked yes)
			(layer "F.Fab")
			(hide yes)
			(effects
				(font
					(size 1.016 1.016)
					(thickness 0.1524)
				)
			)
		)
		(duplicate_pad_numbers_are_jumpers no)
		(fp_line
			(start 0.635 0)
			(end -0.635 0)
			(stroke
				(width 0.508)
				(type default)
			)
			(layer "F.SilkS")
		)
		(fp_rect
			(start -0.9652 1.778)
			(end 0.9652 -1.778)
			(stroke
				(width 0)
				(type default)
			)
			(fill no)
			(layer "F.CrtYd")
		)
		(fp_poly
			(pts
				(xy -0.9652 -1.778) (xy 0.9652 -1.778) (xy 0.9652 1.778) (xy -0.9652 1.778)
			)
			(stroke
				(width 0)
				(type default)
			)
			(fill no)
			(layer "F.Fab")
		)
		(pad "1" smd rect
			(at 0 -0.9652)
			(size 1.397 1.143)
			(layers "F.Cu" "F.Mask" "F.Paste")
			(net "P1V8_STBY")
		)
		(pad "2" smd rect
			(at 0 0.9652)
			(size 1.397 1.143)
			(layers "F.Cu" "F.Mask" "F.Paste")
			(net "GND")
		)
	)
	(footprint ""
		(layer "F.Cu")
		(at 80.6704 -154.5844)
		(property "Reference" "C239"
			(at 0 0 0)
			(layer "F.SilkS")
			(hide yes)
			(effects
				(font
					(size 1.27 1.27)
				)
			)
		)
		(property "Value" "SCD1U16V2KX-3GP"
			(at 1.1811 -2.7051 0)
			(unlocked yes)
			(layer "F.Fab")
			(hide yes)
			(effects
				(font
					(size 1.016 1.016)
					(thickness 0.1524)
				)
			)
		)
		(property "Device Type" "C402H22"
			(at 1.1811 -4.2291 0)
			(unlocked yes)
			(layer "F.Fab")
			(hide yes)
			(effects
				(font
					(size 1.016 1.016)
					(thickness 0.1524)
				)
			)
		)
		(duplicate_pad_numbers_are_jumpers no)
		(fp_rect
			(start -0.4318 0.9525)
			(end 0.4318 -0.9525)
			(stroke
				(width 0)
				(type default)
			)
			(fill no)
			(layer "F.CrtYd")
		)
		(fp_rect
			(start -0.4318 0.9525)
			(end 0.4318 -0.9525)
			(stroke
				(width 0)
				(type default)
			)
			(fill no)
			(layer "F.Fab")
		)
		(pad "1" smd custom
			(at 0 -0.4445)
			(size 0.1524 0.1524)
			(layers "F.Cu" "F.Mask" "F.Paste")
			(net "TPS74801_P1V15_STBY_OUT")
			(options
				(clearance outline)
				(anchor circle)
			)
			(primitives
				(gr_poly
					(pts
						(arc
							(start 0.3048 -0.2032)
							(mid 0.275042 -0.275042)
							(end 0.2032 -0.3048)
						)
						(arc
							(start -0.2032 -0.3048)
							(mid -0.275042 -0.275042)
							(end -0.3048 -0.2032)
						)
						(arc
							(start -0.3048 0.2032)
							(mid -0.275042 0.275042)
							(end -0.2032 0.3048)
						)
						(arc
							(start 0.2032 0.3048)
							(mid 0.275042 0.275042)
							(end 0.3048 0.2032)
						)
					)
					(width 0)
					(fill yes)
				)
			)
		)
		(pad "2" smd custom
			(at 0 0.4445)
			(size 0.1524 0.1524)
			(layers "F.Cu" "F.Mask" "F.Paste")
			(net "GND")
			(options
				(clearance outline)
				(anchor circle)
			)
			(primitives
				(gr_poly
					(pts
						(arc
							(start 0.3048 -0.2032)
							(mid 0.275042 -0.275042)
							(end 0.2032 -0.3048)
						)
						(arc
							(start -0.2032 -0.3048)
							(mid -0.275042 -0.275042)
							(end -0.3048 -0.2032)
						)
						(arc
							(start -0.3048 0.2032)
							(mid -0.275042 0.275042)
							(end -0.2032 0.3048)
						)
						(arc
							(start 0.2032 0.3048)
							(mid 0.275042 0.275042)
							(end 0.3048 0.2032)
						)
					)
					(width 0)
					(fill yes)
				)
			)
		)
	)
	(footprint ""
		(layer "F.Cu")
		(at 91.770708 -122.013472 90)
		(property "Reference" "R796"
			(at 0 0 90)
			(layer "F.SilkS")
			(hide yes)
			(effects
				(font
					(size 1.27 1.27)
				)
			)
		)
		(property "Value" "0R2J-2-GP"
			(at 0.064008 -3.993896 90)
			(unlocked yes)
			(layer "F.Fab")
			(hide yes)
			(effects
				(font
					(size 1.016 1.016)
					(thickness 0.1524)
				)
			)
		)
		(property "Device Type" "R402H16"
			(at 0.064008 -5.517896 90)
			(unlocked yes)
			(layer "F.Fab")
			(hide yes)
			(effects
				(font
					(size 1.016 1.016)
					(thickness 0.1524)
				)
			)
		)
		(duplicate_pad_numbers_are_jumpers no)
		(fp_line
			(start 0.508 -0.9398)
			(end -0.508 -0.9398)
			(stroke
				(width 0.1524)
				(type default)
			)
			(layer "F.SilkS")
		)
		(fp_line
			(start -0.508 -0.9398)
			(end -0.508 0.9398)
			(stroke
				(width 0.1524)
				(type default)
			)
			(layer "F.SilkS")
		)
		(fp_rect
			(start -0.508 0.9398)
			(end 0.508 -0.9398)
			(stroke
				(width 0)
				(type default)
			)
			(fill no)
			(layer "F.CrtYd")
		)
		(fp_rect
			(start -0.508 0.9398)
			(end 0.508 -0.9398)
			(stroke
				(width 0)
				(type default)
			)
			(fill no)
			(layer "F.Fab")
		)
		(pad "1" smd custom
			(at 0 -0.4445 90)
			(size 0.1397 0.1397)
			(layers "F.Cu" "F.Mask" "F.Paste")
			(net "UART_COMP_IN_RX")
			(options
				(clearance outline)
				(anchor circle)
			)
			(primitives
				(gr_poly
					(pts
						(arc
							(start -0.1778 -0.2794)
							(mid -0.249642 -0.249642)
							(end -0.2794 -0.1778)
						)
						(arc
							(start -0.2794 0.1778)
							(mid -0.249642 0.249642)
							(end -0.1778 0.2794)
						)
						(arc
							(start 0.1778 0.2794)
							(mid 0.249642 0.249642)
							(end 0.2794 0.1778)
						)
						(arc
							(start 0.2794 -0.1778)
							(mid 0.249642 -0.249642)
							(end 0.1778 -0.2794)
						)
					)
					(width 0)
					(fill yes)
				)
			)
		)
		(pad "2" smd custom
			(at 0 0.4445 90)
			(size 0.1397 0.1397)
			(layers "F.Cu" "F.Mask" "F.Paste")
			(net "UART_COMP_IN_R_RX")
			(options
				(clearance outline)
				(anchor circle)
			)
			(primitives
				(gr_poly
					(pts
						(arc
							(start -0.1778 -0.2794)
							(mid -0.249642 -0.249642)
							(end -0.2794 -0.1778)
						)
						(arc
							(start -0.2794 0.1778)
							(mid -0.249642 0.249642)
							(end -0.1778 0.2794)
						)
						(arc
							(start 0.1778 0.2794)
							(mid 0.249642 0.249642)
							(end 0.2794 0.1778)
						)
						(arc
							(start 0.2794 -0.1778)
							(mid 0.249642 -0.249642)
							(end 0.1778 -0.2794)
						)
					)
					(width 0)
					(fill yes)
				)
			)
		)
	)
	(footprint ""
		(layer "F.Cu")
		(at 219.447872 -53.483256 90)
		(property "Reference" "C161"
			(at 0 0 90)
			(layer "F.SilkS")
			(hide yes)
			(effects
				(font
					(size 1.27 1.27)
				)
			)
		)
		(property "Value" "SC1U16V3KX-5GP"
			(at 0 -2.8194 90)
			(unlocked yes)
			(layer "F.Fab")
			(hide yes)
			(effects
				(font
					(size 1.016 1.016)
					(thickness 0.1524)
				)
			)
		)
		(property "Device Type" "C603H36"
			(at 0 -4.3434 90)
			(unlocked yes)
			(layer "F.Fab")
			(hide yes)
			(effects
				(font
					(size 1.016 1.016)
					(thickness 0.1524)
				)
			)
		)
		(duplicate_pad_numbers_are_jumpers no)
		(fp_line
			(start 0.508 0)
			(end -0.508 0)
			(stroke
				(width 0.2032)
				(type default)
			)
			(layer "F.SilkS")
		)
		(fp_rect
			(start -0.5842 1.3335)
			(end 0.5842 -1.3335)
			(stroke
				(width 0)
				(type default)
			)
			(fill no)
			(layer "F.CrtYd")
		)
		(fp_rect
			(start -0.5842 1.3335)
			(end 0.5842 -1.3335)
			(stroke
				(width 0)
				(type default)
			)
			(fill no)
			(layer "F.Fab")
		)
		(pad "1" smd custom
			(at 0 -0.762 90)
			(size 0.2159 0.2159)
			(layers "F.Cu" "F.Mask" "F.Paste")
			(net "GND")
			(options
				(clearance outline)
				(anchor circle)
			)
			(primitives
				(gr_poly
					(pts
						(arc
							(start -0.3302 -0.4318)
							(mid -0.402042 -0.402042)
							(end -0.4318 -0.3302)
						)
						(arc
							(start -0.4318 0.3302)
							(mid -0.402042 0.402042)
							(end -0.3302 0.4318)
						)
						(arc
							(start 0.3302 0.4318)
							(mid 0.402042 0.402042)
							(end 0.4318 0.3302)
						)
						(arc
							(start 0.4318 -0.3302)
							(mid 0.402042 -0.402042)
							(end 0.3302 -0.4318)
						)
					)
					(width 0)
					(fill yes)
				)
			)
		)
		(pad "2" smd custom
			(at 0 0.762 90)
			(size 0.2159 0.2159)
			(layers "F.Cu" "F.Mask" "F.Paste")
			(net "P5V_STBY_VREG")
			(options
				(clearance outline)
				(anchor circle)
			)
			(primitives
				(gr_poly
					(pts
						(arc
							(start -0.3302 -0.4318)
							(mid -0.402042 -0.402042)
							(end -0.4318 -0.3302)
						)
						(arc
							(start -0.4318 0.3302)
							(mid -0.402042 0.402042)
							(end -0.3302 0.4318)
						)
						(arc
							(start 0.3302 0.4318)
							(mid 0.402042 0.402042)
							(end 0.4318 0.3302)
						)
						(arc
							(start 0.4318 -0.3302)
							(mid 0.402042 -0.402042)
							(end 0.3302 -0.4318)
						)
					)
					(width 0)
					(fill yes)
				)
			)
		)
	)
)
